# BASEBOARD_FAB2 (Tioga Pass) — schematic netlist excerpt (pin names and nets, part order shuffled) for the footprints in the layout excerpt that follows; sources: Cadence DE-HDL packaged netlist, KiCad conversion of Wiwynn_Tioga_Pass_MB.brd

R25W16  120R2F-GP  1%  pkg RCL_GP  page 151 : \1\ = GND ; \2\ = BMC_M_A4
C4E6  SC1U10V2KX-4-GP  10%  pkg SMD-BCG6  page 202 : \1\ = P5V_STBY ; \2\ = GND
R9G1  RES  150.0 1% CHIP  pkg 0402  page 141 : A = LED_LAN_1_N ; B = LED_LAN_1_R_N

(kicad_pcb
	(version 20260206)
	(generator "pcbnew")
	(generator_version "10.0")
	(general
		(thickness 1.6)
		(legacy_teardrops no)
	)
	(paper "A4")
	(title_block
		(title "Wiwynn_Tioga_Pass_MB.brd")
		(comment 1 "Tioga Pass / footprints 2640-2642 of 4770")
	)
	(layers
		(0 "F.Cu" signal "TOP")
		(4 "In1.Cu" signal "L2GND")
		(6 "In2.Cu" signal "L3")
		(8 "In3.Cu" signal "L4GND")
		(10 "In4.Cu" signal "L5")
		(12 "In5.Cu" signal "L6GND")
		(14 "In6.Cu" signal "L7VCC")
		(16 "In7.Cu" signal "L8VCC")
		(18 "In8.Cu" signal "L9GND")
		(20 "In9.Cu" signal "L10")
		(22 "In10.Cu" signal "L11GND")
		(24 "In11.Cu" signal "L12")
		(26 "In12.Cu" signal "L13GND")
		(2 "B.Cu" signal "BOTTOM")
		(9 "F.Adhes" user "F.Adhesive")
		(11 "B.Adhes" user "B.Adhesive")
		(13 "F.Paste" user "Package Geometry/Pastemask Top")
		(15 "B.Paste" user "Package Geometry/Pastemask Bottom")
		(5 "F.SilkS" user "Ref Des/Silkscreen Top")
		(7 "B.SilkS" user "Ref Des/Silkscreen Bottom")
		(1 "F.Mask" user "Board Geometry/Soldermask Top")
		(3 "B.Mask" user "Board Geometry/Soldermask Bottom")
		(17 "Dwgs.User" user "User.Drawings")
		(19 "Cmts.User" user "User.Comments")
		(21 "Eco1.User" user "User.Eco1")
		(23 "Eco2.User" user "User.Eco2")
		(25 "Edge.Cuts" user "Board Geometry/Outline")
		(27 "Margin" user)
		(31 "F.CrtYd" user "Package Geometry/Place Bound Top")
		(29 "B.CrtYd" user "Package Geometry/Place Bound Bottom")
		(35 "F.Fab" user "Ref Des/Assembly Top")
		(33 "B.Fab" user "Ref Des/Assembly Bottom")
	)
	(footprint ""
		(layer "B.Cu")
		(at 198.615808 -53.127402 90)
		(property "Reference" "C4E6"
			(at 0 0 90)
			(layer "B.SilkS")
			(hide yes)
			(effects
				(font
					(size 1.27 1.27)
				)
				(justify mirror)
			)
		)
		(property "Value" "*"
			(at -1.1811 -2.8194 90)
			(unlocked yes)
			(layer "B.Fab")
			(hide yes)
			(effects
				(font
					(size 1.27 1.016)
					(thickness 0.1524)
				)
				(justify mirror)
			)
		)
		(property "Device Type" "SC1U10V2KX-4-GP_SMD-BCG6-SC1U1A"
			(at -1.1811 -4.3434 90)
			(unlocked yes)
			(layer "B.Fab")
			(hide yes)
			(effects
				(font
					(size 1.27 1.016)
					(thickness 0.1524)
				)
				(justify mirror)
			)
		)
		(duplicate_pad_numbers_are_jumpers no)
		(fp_rect
			(start 0.4318 0.9525)
			(end -0.4318 -0.9525)
			(stroke
				(width 0)
				(type default)
			)
			(fill no)
			(layer "B.CrtYd")
		)
		(fp_rect
			(start 0.4318 0.9525)
			(end -0.4318 -0.9525)
			(stroke
				(width 0)
				(type default)
			)
			(fill no)
			(layer "B.Fab")
		)
		(pad "1" smd custom
			(at 0 -0.4445 270)
			(size 0.1524 0.1524)
			(layers "B.Cu" "B.Mask" "B.Paste")
			(net "P5V_STBY")
			(options
				(clearance outline)
				(anchor circle)
			)
			(primitives
				(gr_poly
					(pts
						(arc
							(start 0.3048 0.2032)
							(mid 0.275042 0.275042)
							(end 0.2032 0.3048)
						)
						(arc
							(start -0.2032 0.3048)
							(mid -0.275042 0.275042)
							(end -0.3048 0.2032)
						)
						(arc
							(start -0.3048 -0.2032)
							(mid -0.275042 -0.275042)
							(end -0.2032 -0.3048)
						)
						(arc
							(start 0.2032 -0.3048)
							(mid 0.275042 -0.275042)
							(end 0.3048 -0.2032)
						)
					)
					(width 0)
					(fill yes)
				)
			)
		)
		(pad "2" smd custom
			(at 0 0.4445 270)
			(size 0.1524 0.1524)
			(layers "B.Cu" "B.Mask" "B.Paste")
			(net "GND")
			(options
				(clearance outline)
				(anchor circle)
			)
			(primitives
				(gr_poly
					(pts
						(arc
							(start 0.3048 0.2032)
							(mid 0.275042 0.275042)
							(end 0.2032 0.3048)
						)
						(arc
							(start -0.2032 0.3048)
							(mid -0.275042 0.275042)
							(end -0.3048 0.2032)
						)
						(arc
							(start -0.3048 -0.2032)
							(mid -0.275042 -0.275042)
							(end -0.2032 -0.3048)
						)
						(arc
							(start 0.2032 -0.3048)
							(mid 0.275042 -0.275042)
							(end 0.3048 -0.2032)
						)
					)
					(width 0)
					(fill yes)
				)
			)
		)
	)
	(footprint ""
		(layer "B.Cu")
		(at 443.405006 -41.648126 180)
		(property "Reference" "R25W16"
			(at 0 0 0)
			(layer "B.SilkS")
			(hide yes)
			(effects
				(font
					(size 1.27 1.27)
				)
				(justify mirror)
			)
		)
		(property "Value" "*"
			(at -0.064008 -4.108196 180)
			(unlocked yes)
			(layer "B.Fab")
			(hide yes)
			(effects
				(font
					(size 1.27 1.016)
					(thickness 0.1524)
				)
				(justify mirror)
			)
		)
		(property "Device Type" "120R2F-GP_RCL_GP-120R2F-GP,64.A"
			(at -0.064008 -5.632196 180)
			(unlocked yes)
			(layer "B.Fab")
			(hide yes)
			(effects
				(font
					(size 1.27 1.016)
					(thickness 0.1524)
				)
				(justify mirror)
			)
		)
		(duplicate_pad_numbers_are_jumpers no)
		(fp_line
			(start 0.508 -0.9398)
			(end 0.508 0.9398)
			(stroke
				(width 0.1524)
				(type default)
			)
			(layer "B.SilkS")
		)
		(fp_line
			(start -0.508 -0.9398)
			(end 0.508 -0.9398)
			(stroke
				(width 0.1524)
				(type default)
			)
			(layer "B.SilkS")
		)
		(fp_rect
			(start 0.508 0.9398)
			(end -0.508 -0.9398)
			(stroke
				(width 0)
				(type default)
			)
			(fill no)
			(layer "B.CrtYd")
		)
		(fp_rect
			(start 0.508 0.9398)
			(end -0.508 -0.9398)
			(stroke
				(width 0)
				(type default)
			)
			(fill no)
			(layer "B.Fab")
		)
		(pad "1" smd custom
			(at 0 -0.4445)
			(size 0.1397 0.1397)
			(layers "B.Cu" "B.Mask" "B.Paste")
			(net "GND")
			(options
				(clearance outline)
				(anchor circle)
			)
			(primitives
				(gr_poly
					(pts
						(arc
							(start -0.1778 0.2794)
							(mid -0.249642 0.249642)
							(end -0.2794 0.1778)
						)
						(arc
							(start -0.2794 -0.1778)
							(mid -0.249642 -0.249642)
							(end -0.1778 -0.2794)
						)
						(arc
							(start 0.1778 -0.2794)
							(mid 0.249642 -0.249642)
							(end 0.2794 -0.1778)
						)
						(arc
							(start 0.2794 0.1778)
							(mid 0.249642 0.249642)
							(end 0.1778 0.2794)
						)
					)
					(width 0)
					(fill yes)
				)
			)
		)
		(pad "2" smd custom
			(at 0 0.4445)
			(size 0.1397 0.1397)
			(layers "B.Cu" "B.Mask" "B.Paste")
			(net "BMC_M_A4")
			(options
				(clearance outline)
				(anchor circle)
			)
			(primitives
				(gr_poly
					(pts
						(arc
							(start -0.1778 0.2794)
							(mid -0.249642 0.249642)
							(end -0.2794 0.1778)
						)
						(arc
							(start -0.2794 -0.1778)
							(mid -0.249642 -0.249642)
							(end -0.1778 -0.2794)
						)
						(arc
							(start 0.1778 -0.2794)
							(mid 0.249642 -0.249642)
							(end 0.2794 -0.1778)
						)
						(arc
							(start 0.2794 0.1778)
							(mid 0.249642 0.249642)
							(end 0.1778 0.2794)
						)
					)
					(width 0)
					(fill yes)
				)
			)
		)
	)
	(footprint ""
		(layer "B.Cu")
		(at 479.16211 4.716272 180)
		(property "Reference" "R9G1"
			(at 0 0 0)
			(layer "B.SilkS")
			(hide yes)
			(effects
				(font
					(size 1.27 1.27)
				)
				(justify mirror)
			)
		)
		(property "Value" ""
			(at 0 0 0)
			(layer "B.Fab")
			(effects
				(font
					(size 1.27 1.27)
				)
				(justify mirror)
			)
		)
		(duplicate_pad_numbers_are_jumpers no)
		(fp_poly
			(pts
				(xy 0.2794 -0.1016) (xy -0.2794 -0.1016) (xy -0.2794 0.9906) (xy 0.2794 0.9906)
			)
			(stroke
				(width 0)
				(type default)
			)
			(fill no)
			(layer "B.CrtYd")
		)
		(fp_line
			(start 0.2794 0.9906)
			(end -0.2794 0.9906)
			(stroke
				(width 0.1)
				(type default)
			)
			(layer "B.Fab")
		)
		(fp_line
			(start 0.2794 -0.1016)
			(end 0.2794 0.9906)
			(stroke
				(width 0.1)
				(type default)
			)
			(layer "B.Fab")
		)
		(fp_line
			(start -0.2794 0.9906)
			(end -0.2794 -0.1016)
			(stroke
				(width 0.1)
				(type default)
			)
			(layer "B.Fab")
		)
		(fp_line
			(start -0.2794 -0.1016)
			(end 0.2794 -0.1016)
			(stroke
				(width 0.1)
				(type default)
			)
			(layer "B.Fab")
		)
		(pad "1" smd rect
			(at 0 0)
			(size 0.508 0.508)
			(layers "B.Cu" "B.Mask" "B.Paste")
			(net "LED_LAN_1_N")
		)
		(pad "2" smd rect
			(at 0 0.889)
			(size 0.508 0.508)
			(layers "B.Cu" "B.Mask" "B.Paste")
			(net "LED_LAN_1_R_N")
		)
		(zone
			(layer "B.Cu")
			(hatch none 0.5)
			(connect_pads
				(clearance 0)
			)
			(min_thickness 0.25)
			(keepout
				(tracks not_allowed)
				(vias allowed)
				(pads allowed)
				(copperpour not_allowed)
				(footprints allowed)
			)
			(placement
				(enabled no)
				(sheetname "")
			)
			(fill
				(thermal_gap 0.5)
				(thermal_bridge_width 0.5)
				(island_removal_mode 0)
			)
			(polygon
				(pts
					(xy 478.90811 4.081272) (xy 479.41611 4.081272) (xy 479.41611 4.462272) (xy 478.90811 4.462272)
				)
			)
		)
		(zone
			(layer "B.Cu")
			(hatch none 0.5)
			(connect_pads
				(clearance 0)
			)
			(min_thickness 0.25)
			(keepout
				(tracks allowed)
				(vias not_allowed)
				(pads allowed)
				(copperpour not_allowed)
				(footprints allowed)
			)
			(placement
				(enabled no)
				(sheetname "")
			)
			(fill
				(thermal_gap 0.5)
				(thermal_bridge_width 0.5)
				(island_removal_mode 0)
			)
			(polygon
				(pts
					(xy 478.90811 4.462272) (xy 479.41611 4.462272) (xy 479.41611 4.081272) (xy 478.90811 4.081272)
				)
			)
		)
	)
)
